# T6G (Grand Teton) — schematic netlist excerpt (pin names and nets, part order shuffled) for the footprints in the layout excerpt that follows; sources: Cadence DE-HDL packaged netlist, KiCad conversion of 04192023_DAF0TMB3IC0_F0TG_MB_C_brd_V02_OCP.brd

R95  Q_RES  1K 1% EMPTY  pkg 0402LF  page 92 : A = P3V3 ; B = PWRGD_CHGL_CPU0
C3918  Q_CAP  22UF 4V 20% X6S  pkg C0402  page 74 : A = PVDDCR_SOC_P1 ; B = GND

(kicad_pcb
	(version 20260206)
	(generator "pcbnew")
	(generator_version "10.0")
	(general
		(thickness 1.6)
		(legacy_teardrops no)
	)
	(paper "A4")
	(title_block
		(title "04192023_DAF0TMB3IC0_F0TG_MB_C_brd_V02_OCP.brd")
		(comment 1 "Grand Teton / footprints 8172-8173 of 8354")
	)
	(layers
		(0 "F.Cu" signal "TOP")
		(4 "In1.Cu" signal "GND")
		(6 "In2.Cu" signal "IN1")
		(8 "In3.Cu" signal "GND1")
		(10 "In4.Cu" signal "IN2")
		(12 "In5.Cu" signal "GND2")
		(14 "In6.Cu" signal "IN3")
		(16 "In7.Cu" signal "GND3")
		(18 "In8.Cu" signal "VCC")
		(20 "In9.Cu" signal "VCC1")
		(22 "In10.Cu" signal "GND4")
		(24 "In11.Cu" signal "IN4")
		(26 "In12.Cu" signal "GND5")
		(28 "In13.Cu" signal "IN5")
		(30 "In14.Cu" signal "GND6")
		(32 "In15.Cu" signal "IN6")
		(34 "In16.Cu" signal "GND7")
		(2 "B.Cu" signal "BOTTOM")
		(9 "F.Adhes" user "F.Adhesive")
		(11 "B.Adhes" user "B.Adhesive")
		(13 "F.Paste" user "Package Geometry/Pastemask Top")
		(15 "B.Paste" user "Package Geometry/Pastemask Bottom")
		(5 "F.SilkS" user "Ref Des/Silkscreen Top")
		(7 "B.SilkS" user "Ref Des/Silkscreen Bottom")
		(1 "F.Mask" user "Board Geometry/Soldermask Top")
		(3 "B.Mask" user "Board Geometry/Soldermask Bottom")
		(17 "Dwgs.User" user "User.Drawings")
		(19 "Cmts.User" user "User.Comments")
		(21 "Eco1.User" user "User.Eco1")
		(23 "Eco2.User" user "User.Eco2")
		(25 "Edge.Cuts" user "Board Geometry/Outline")
		(27 "Margin" user)
		(31 "F.CrtYd" user "Package Geometry/Place Bound Top")
		(29 "B.CrtYd" user "Package Geometry/Place Bound Bottom")
		(35 "F.Fab" user "Ref Des/Assembly Top")
		(33 "B.Fab" user "Ref Des/Assembly Bottom")
	)
	(footprint ""
		(layer "B.Cu")
		(at 414.096454 -191.20231)
		(property "Reference" "R95"
			(at 0 0 0)
			(layer "B.SilkS")
			(hide yes)
			(effects
				(font
					(size 1.27 1.27)
				)
				(justify mirror)
			)
		)
		(property "Value" ""
			(at 0 0 0)
			(layer "B.Fab")
			(effects
				(font
					(size 1.27 1.27)
				)
				(justify mirror)
			)
		)
		(duplicate_pad_numbers_are_jumpers no)
		(fp_line
			(start -0.7874 -0.4064)
			(end -0.7874 0.4064)
			(stroke
				(width 0.1524)
				(type default)
			)
			(layer "B.SilkS")
		)
		(fp_line
			(start -0.7874 0.4064)
			(end 0.7874 0.4064)
			(stroke
				(width 0.1524)
				(type default)
			)
			(layer "B.SilkS")
		)
		(fp_line
			(start 0.7874 -0.4064)
			(end -0.7874 -0.4064)
			(stroke
				(width 0.1524)
				(type default)
			)
			(layer "B.SilkS")
		)
		(fp_line
			(start 0.7874 0.4064)
			(end 0.7874 -0.4064)
			(stroke
				(width 0.1524)
				(type default)
			)
			(layer "B.SilkS")
		)
		(fp_line
			(start -0.67945 -0.3048)
			(end -0.67945 0.3048)
			(stroke
				(width 0.1)
				(type default)
			)
			(layer "B.Fab")
		)
		(fp_line
			(start -0.67945 0.3048)
			(end -0.120396 0.3048)
			(stroke
				(width 0.1)
				(type default)
			)
			(layer "B.Fab")
		)
		(fp_line
			(start -0.12065 -0.3048)
			(end -0.67945 -0.3048)
			(stroke
				(width 0.1)
				(type default)
			)
			(layer "B.Fab")
		)
		(fp_line
			(start -0.12065 -0.2794)
			(end -0.12065 -0.3048)
			(stroke
				(width 0.1)
				(type default)
			)
			(layer "B.Fab")
		)
		(fp_line
			(start -0.120396 0.2794)
			(end 0.12065 0.2794)
			(stroke
				(width 0.1)
				(type default)
			)
			(layer "B.Fab")
		)
		(fp_line
			(start -0.120396 0.3048)
			(end -0.120396 0.2794)
			(stroke
				(width 0.1)
				(type default)
			)
			(layer "B.Fab")
		)
		(fp_line
			(start 0.12065 -0.305054)
			(end 0.12065 -0.2794)
			(stroke
				(width 0.1)
				(type default)
			)
			(layer "B.Fab")
		)
		(fp_line
			(start 0.12065 -0.2794)
			(end -0.12065 -0.2794)
			(stroke
				(width 0.1)
				(type default)
			)
			(layer "B.Fab")
		)
		(fp_line
			(start 0.12065 0.2794)
			(end 0.12065 0.3048)
			(stroke
				(width 0.1)
				(type default)
			)
			(layer "B.Fab")
		)
		(fp_line
			(start 0.12065 0.3048)
			(end 0.67945 0.3048)
			(stroke
				(width 0.1)
				(type default)
			)
			(layer "B.Fab")
		)
		(fp_line
			(start 0.67945 -0.305054)
			(end 0.12065 -0.305054)
			(stroke
				(width 0.1)
				(type default)
			)
			(layer "B.Fab")
		)
		(fp_line
			(start 0.67945 0.3048)
			(end 0.67945 -0.305054)
			(stroke
				(width 0.1)
				(type default)
			)
			(layer "B.Fab")
		)
		(pad "1" smd circle
			(at 0.40005 0 180)
			(size 0 0)
			(layers "B.Cu" "B.Mask" "B.Paste")
			(net "P3V3")
		)
		(pad "2" smd circle
			(at -0.40005 0 180)
			(size 0 0)
			(layers "B.Cu" "B.Mask" "B.Paste")
			(net "PWRGD_CHGL_CPU0")
		)
	)
	(footprint ""
		(layer "B.Cu")
		(at 123.611386 -255.845564)
		(property "Reference" "C3918"
			(at 0 0 0)
			(layer "B.SilkS")
			(hide yes)
			(effects
				(font
					(size 1.27 1.27)
				)
				(justify mirror)
			)
		)
		(property "Value" ""
			(at 0 0 0)
			(layer "B.Fab")
			(effects
				(font
					(size 1.27 1.27)
				)
				(justify mirror)
			)
		)
		(duplicate_pad_numbers_are_jumpers no)
		(fp_line
			(start -0.7874 -0.4064)
			(end -0.7874 0.4064)
			(stroke
				(width 0.1524)
				(type default)
			)
			(layer "B.SilkS")
		)
		(fp_line
			(start -0.7874 0.4064)
			(end 0.7874 0.4064)
			(stroke
				(width 0.1524)
				(type default)
			)
			(layer "B.SilkS")
		)
		(fp_line
			(start 0.7874 -0.4064)
			(end -0.7874 -0.4064)
			(stroke
				(width 0.1524)
				(type default)
			)
			(layer "B.SilkS")
		)
		(fp_line
			(start 0.7874 0.4064)
			(end 0.7874 -0.4064)
			(stroke
				(width 0.1524)
				(type default)
			)
			(layer "B.SilkS")
		)
		(fp_line
			(start -0.67945 -0.3048)
			(end -0.67945 0.3048)
			(stroke
				(width 0.1)
				(type default)
			)
			(layer "B.Fab")
		)
		(fp_line
			(start -0.67945 0.3048)
			(end -0.120396 0.3048)
			(stroke
				(width 0.1)
				(type default)
			)
			(layer "B.Fab")
		)
		(fp_line
			(start -0.12065 -0.3048)
			(end -0.67945 -0.3048)
			(stroke
				(width 0.1)
				(type default)
			)
			(layer "B.Fab")
		)
		(fp_line
			(start -0.12065 -0.2794)
			(end -0.12065 -0.3048)
			(stroke
				(width 0.1)
				(type default)
			)
			(layer "B.Fab")
		)
		(fp_line
			(start -0.120396 0.2794)
			(end 0.12065 0.2794)
			(stroke
				(width 0.1)
				(type default)
			)
			(layer "B.Fab")
		)
		(fp_line
			(start -0.120396 0.3048)
			(end -0.120396 0.2794)
			(stroke
				(width 0.1)
				(type default)
			)
			(layer "B.Fab")
		)
		(fp_line
			(start 0.12065 -0.305054)
			(end 0.12065 -0.2794)
			(stroke
				(width 0.1)
				(type default)
			)
			(layer "B.Fab")
		)
		(fp_line
			(start 0.12065 -0.2794)
			(end -0.12065 -0.2794)
			(stroke
				(width 0.1)
				(type default)
			)
			(layer "B.Fab")
		)
		(fp_line
			(start 0.12065 0.2794)
			(end 0.12065 0.3048)
			(stroke
				(width 0.1)
				(type default)
			)
			(layer "B.Fab")
		)
		(fp_line
			(start 0.12065 0.3048)
			(end 0.67945 0.3048)
			(stroke
				(width 0.1)
				(type default)
			)
			(layer "B.Fab")
		)
		(fp_line
			(start 0.67945 -0.305054)
			(end 0.12065 -0.305054)
			(stroke
				(width 0.1)
				(type default)
			)
			(layer "B.Fab")
		)
		(fp_line
			(start 0.67945 0.3048)
			(end 0.67945 -0.305054)
			(stroke
				(width 0.1)
				(type default)
			)
			(layer "B.Fab")
		)
		(pad "1" smd circle
			(at 0.40005 0 180)
			(size 0 0)
			(layers "B.Cu" "B.Mask" "B.Paste")
			(net "PVDDCR_SOC_P1")
		)
		(pad "2" smd circle
			(at -0.40005 0 180)
			(size 0 0)
			(layers "B.Cu" "B.Mask" "B.Paste")
			(net "GND")
		)
	)
)
